(kicad_pcb
	(version 20260206)
	(generator "pcbnew")
	(generator_version "10.0")
	(general
		(thickness 1.6)
		(legacy_teardrops no)
	)
	(paper "A4")
	(title_block
		(title "Bryce Canyon_R.DPB_16317-1_OCP.brd")
		(comment 1 "Bryce Canyon / footprints 452-460 of 2099")
	)
	(layers
		(0 "F.Cu" signal "TOP")
		(4 "In1.Cu" signal "L2GND")
		(6 "In2.Cu" signal "L3")
		(8 "In3.Cu" signal "L4VCC")
		(10 "In4.Cu" signal "L5VCC")
		(12 "In5.Cu" signal "L6")
		(14 "In6.Cu" signal "L7GND")
		(2 "B.Cu" signal "BOTTOM")
		(9 "F.Adhes" user "F.Adhesive")
		(11 "B.Adhes" user "B.Adhesive")
		(13 "F.Paste" user "Package Geometry/Pastemask Top")
		(15 "B.Paste" user "Package Geometry/Pastemask Bottom")
		(5 "F.SilkS" user "Ref Des/Silkscreen Top")
		(7 "B.SilkS" user "Ref Des/Silkscreen Bottom")
		(1 "F.Mask" user "Board Geometry/Soldermask Top")
		(3 "B.Mask" user "Board Geometry/Soldermask Bottom")
		(17 "Dwgs.User" user "User.Drawings")
		(19 "Cmts.User" user "User.Comments")
		(21 "Eco1.User" user "User.Eco1")
		(23 "Eco2.User" user "User.Eco2")
		(25 "Edge.Cuts" user "Board Geometry/Outline")
		(27 "Margin" user)
		(31 "F.CrtYd" user "Package Geometry/Place Bound Top")
		(29 "B.CrtYd" user "Package Geometry/Place Bound Bottom")
		(35 "F.Fab" user "Ref Des/Assembly Top")
		(33 "B.Fab" user "Ref Des/Assembly Bottom")
	)
	(footprint ""
		(layer "F.Cu")
		(at 141.478 -133.096 180)
		(property "Reference" "R454"
			(at 0 0 180)
			(layer "F.SilkS")
			(hide yes)
			(effects
				(font
					(size 1.27 1.27)
				)
			)
		)
		(property "Value" "200KR2F-L-GP"
			(at 0.064008 -3.993896 180)
			(unlocked yes)
			(layer "F.Fab")
			(hide yes)
			(effects
				(font
					(size 1.016 1.016)
					(thickness 0.1524)
				)
			)
		)
		(property "Device Type" "R402H16"
			(at 0.064008 -5.517896 180)
			(unlocked yes)
			(layer "F.Fab")
			(hide yes)
			(effects
				(font
					(size 1.016 1.016)
					(thickness 0.1524)
				)
			)
		)
		(duplicate_pad_numbers_are_jumpers no)
		(fp_line
			(start 0.508 -0.9398)
			(end -0.508 -0.9398)
			(stroke
				(width 0.1524)
				(type default)
			)
			(layer "F.SilkS")
		)
		(fp_line
			(start -0.508 -0.9398)
			(end -0.508 0.9398)
			(stroke
				(width 0.1524)
				(type default)
			)
			(layer "F.SilkS")
		)
		(fp_rect
			(start -0.508 0.9398)
			(end 0.508 -0.9398)
			(stroke
				(width 0)
				(type default)
			)
			(fill no)
			(layer "F.CrtYd")
		)
		(fp_rect
			(start -0.508 0.9398)
			(end 0.508 -0.9398)
			(stroke
				(width 0)
				(type default)
			)
			(fill no)
			(layer "F.Fab")
		)
		(pad "1" smd custom
			(at 0 -0.4445 180)
			(size 0.1397 0.1397)
			(layers "F.Cu" "F.Mask" "F.Paste")
			(net "SW_HDD_R16")
			(options
				(clearance outline)
				(anchor circle)
			)
			(primitives
				(gr_poly
					(pts
						(arc
							(start -0.1778 -0.2794)
							(mid -0.249642 -0.249642)
							(end -0.2794 -0.1778)
						)
						(arc
							(start -0.2794 0.1778)
							(mid -0.249642 0.249642)
							(end -0.1778 0.2794)
						)
						(arc
							(start 0.1778 0.2794)
							(mid 0.249642 0.249642)
							(end 0.2794 0.1778)
						)
						(arc
							(start 0.2794 -0.1778)
							(mid 0.249642 -0.249642)
							(end 0.1778 -0.2794)
						)
					)
					(width 0)
					(fill yes)
				)
			)
		)
		(pad "2" smd custom
			(at 0 0.4445 180)
			(size 0.1397 0.1397)
			(layers "F.Cu" "F.Mask" "F.Paste")
			(net "SW_HDD_N16")
			(options
				(clearance outline)
				(anchor circle)
			)
			(primitives
				(gr_poly
					(pts
						(arc
							(start -0.1778 -0.2794)
							(mid -0.249642 -0.249642)
							(end -0.2794 -0.1778)
						)
						(arc
							(start -0.2794 0.1778)
							(mid -0.249642 0.249642)
							(end -0.1778 0.2794)
						)
						(arc
							(start 0.1778 0.2794)
							(mid 0.249642 0.249642)
							(end 0.2794 0.1778)
						)
						(arc
							(start 0.2794 -0.1778)
							(mid 0.249642 -0.249642)
							(end 0.1778 -0.2794)
						)
					)
					(width 0)
					(fill yes)
				)
			)
		)
	)
	(footprint ""
		(layer "F.Cu")
		(at 460.4512 -9.7028 -90)
		(property "Reference" "TP3"
			(at 0 0 270)
			(layer "F.SilkS")
			(hide yes)
			(effects
				(font
					(size 1.27 1.27)
				)
			)
		)
		(property "Value" "*"
			(at -0.0508 -1.6764 270)
			(unlocked yes)
			(layer "F.Fab")
			(hide yes)
			(effects
				(font
					(size 1.016 1.016)
					(thickness 0.1524)
				)
			)
		)
		(property "Device Type" "TPAD32"
			(at -0.0508 -3.2004 270)
			(unlocked yes)
			(layer "F.Fab")
			(hide yes)
			(effects
				(font
					(size 1.016 1.016)
					(thickness 0.1524)
				)
			)
		)
		(duplicate_pad_numbers_are_jumpers no)
		(fp_poly
			(pts
				(arc
					(start 0 -0.4064)
					(mid 0 0.4064)
					(end 0 -0.4064)
				)
			)
			(stroke
				(width 0)
				(type default)
			)
			(fill no)
			(layer "F.CrtYd")
		)
		(fp_poly
			(pts
				(arc
					(start 0 -0.7112)
					(mid 0 0.7112)
					(end 0 -0.7112)
				)
			)
			(stroke
				(width 0)
				(type default)
			)
			(fill no)
			(layer "F.Fab")
		)
		(pad "1" smd circle
			(at 0 0 270)
			(size 0.8128 0.8128)
			(layers "F.Cu" "F.Mask" "F.Paste")
			(net "TEMP2_ALERT")
		)
	)
	(footprint ""
		(layer "F.Cu")
		(at 118.237 -14.605 90)
		(property "Reference" "R708"
			(at 0 0 90)
			(layer "F.SilkS")
			(hide yes)
			(effects
				(font
					(size 1.27 1.27)
				)
			)
		)
		(property "Value" "0R2J-2-GP"
			(at 0.064008 -3.993896 90)
			(unlocked yes)
			(layer "F.Fab")
			(hide yes)
			(effects
				(font
					(size 1.016 1.016)
					(thickness 0.1524)
				)
			)
		)
		(property "Device Type" "R402H16"
			(at 0.064008 -5.517896 90)
			(unlocked yes)
			(layer "F.Fab")
			(hide yes)
			(effects
				(font
					(size 1.016 1.016)
					(thickness 0.1524)
				)
			)
		)
		(duplicate_pad_numbers_are_jumpers no)
		(fp_line
			(start 0.508 -0.9398)
			(end -0.508 -0.9398)
			(stroke
				(width 0.1524)
				(type default)
			)
			(layer "F.SilkS")
		)
		(fp_line
			(start -0.508 -0.9398)
			(end -0.508 0.9398)
			(stroke
				(width 0.1524)
				(type default)
			)
			(layer "F.SilkS")
		)
		(fp_rect
			(start -0.508 0.9398)
			(end 0.508 -0.9398)
			(stroke
				(width 0)
				(type default)
			)
			(fill no)
			(layer "F.CrtYd")
		)
		(fp_rect
			(start -0.508 0.9398)
			(end 0.508 -0.9398)
			(stroke
				(width 0)
				(type default)
			)
			(fill no)
			(layer "F.Fab")
		)
		(pad "1" smd custom
			(at 0 -0.4445 90)
			(size 0.1397 0.1397)
			(layers "F.Cu" "F.Mask" "F.Paste")
			(net "SW_HDD_G27")
			(options
				(clearance outline)
				(anchor circle)
			)
			(primitives
				(gr_poly
					(pts
						(arc
							(start -0.1778 -0.2794)
							(mid -0.249642 -0.249642)
							(end -0.2794 -0.1778)
						)
						(arc
							(start -0.2794 0.1778)
							(mid -0.249642 0.249642)
							(end -0.1778 0.2794)
						)
						(arc
							(start 0.1778 0.2794)
							(mid 0.249642 0.249642)
							(end 0.2794 0.1778)
						)
						(arc
							(start 0.2794 -0.1778)
							(mid 0.249642 -0.249642)
							(end 0.1778 -0.2794)
						)
					)
					(width 0)
					(fill yes)
				)
			)
		)
		(pad "2" smd custom
			(at 0 0.4445 90)
			(size 0.1397 0.1397)
			(layers "F.Cu" "F.Mask" "F.Paste")
			(net "SW_HDD_R27")
			(options
				(clearance outline)
				(anchor circle)
			)
			(primitives
				(gr_poly
					(pts
						(arc
							(start -0.1778 -0.2794)
							(mid -0.249642 -0.249642)
							(end -0.2794 -0.1778)
						)
						(arc
							(start -0.2794 0.1778)
							(mid -0.249642 0.249642)
							(end -0.1778 0.2794)
						)
						(arc
							(start 0.1778 0.2794)
							(mid 0.249642 0.249642)
							(end 0.2794 0.1778)
						)
						(arc
							(start 0.2794 -0.1778)
							(mid 0.249642 -0.249642)
							(end 0.1778 -0.2794)
						)
					)
					(width 0)
					(fill yes)
				)
			)
		)
	)
	(footprint ""
		(layer "F.Cu")
		(at 479.384614 -14.660626 -90)
		(property "Reference" "C484"
			(at 0 0 270)
			(layer "F.SilkS")
			(hide yes)
			(effects
				(font
					(size 1.27 1.27)
				)
			)
		)
		(property "Value" "SCD01U16V1KX-GP"
			(at -2.8321 -1.7399 270)
			(unlocked yes)
			(layer "F.Fab")
			(hide yes)
			(effects
				(font
					(size 1.016 1.016)
					(thickness 0.1524)
				)
			)
		)
		(property "Device Type" "C0201H13"
			(at -2.8321 -3.2639 270)
			(unlocked yes)
			(layer "F.Fab")
			(hide yes)
			(effects
				(font
					(size 1.016 1.016)
					(thickness 0.1524)
				)
			)
		)
		(duplicate_pad_numbers_are_jumpers no)
		(fp_rect
			(start -0.2794 0.6477)
			(end 0.2794 -0.6477)
			(stroke
				(width 0)
				(type default)
			)
			(fill no)
			(layer "F.CrtYd")
		)
		(fp_rect
			(start -0.2794 0.6477)
			(end 0.2794 -0.6477)
			(stroke
				(width 0)
				(type default)
			)
			(fill no)
			(layer "F.Fab")
		)
		(pad "1" smd custom
			(at 0 -0.2794 270)
			(size 0.0762 0.0762)
			(layers "F.Cu" "F.Mask" "F.Paste")
			(net "SAS_HDD_RX_P35")
			(options
				(clearance outline)
				(anchor circle)
			)
			(primitives
				(gr_poly
					(pts
						(arc
							(start 0.1524 -0.127)
							(mid 0.137521 -0.162921)
							(end 0.1016 -0.1778)
						)
						(arc
							(start -0.1016 -0.1778)
							(mid -0.137521 -0.162921)
							(end -0.1524 -0.127)
						)
						(arc
							(start -0.1524 0.127)
							(mid -0.137521 0.162921)
							(end -0.1016 0.1778)
						)
						(arc
							(start 0.1016 0.1778)
							(mid 0.137521 0.162921)
							(end 0.1524 0.127)
						)
					)
					(width 0)
					(fill yes)
				)
			)
		)
		(pad "2" smd custom
			(at 0 0.2794 270)
			(size 0.0762 0.0762)
			(layers "F.Cu" "F.Mask" "F.Paste")
			(net "PHY_SCC_B_TO_DRV_B_35_DP")
			(options
				(clearance outline)
				(anchor circle)
			)
			(primitives
				(gr_poly
					(pts
						(arc
							(start 0.1524 -0.127)
							(mid 0.137521 -0.162921)
							(end 0.1016 -0.1778)
						)
						(arc
							(start -0.1016 -0.1778)
							(mid -0.137521 -0.162921)
							(end -0.1524 -0.127)
						)
						(arc
							(start -0.1524 0.127)
							(mid -0.137521 0.162921)
							(end -0.1016 0.1778)
						)
						(arc
							(start 0.1016 0.1778)
							(mid 0.137521 0.162921)
							(end 0.1524 0.127)
						)
					)
					(width 0)
					(fill yes)
				)
			)
		)
	)
	(footprint ""
		(layer "F.Cu")
		(at 50.419 -35.687 90)
		(property "Reference" "R646"
			(at 0 0 90)
			(layer "F.SilkS")
			(hide yes)
			(effects
				(font
					(size 1.27 1.27)
				)
			)
		)
		(property "Value" "2R6F-GP"
			(at -0.0508 -4.8514 90)
			(unlocked yes)
			(layer "F.Fab")
			(hide yes)
			(effects
				(font
					(size 1.016 1.016)
					(thickness 0.1524)
				)
			)
		)
		(property "Device Type" "R1206H26"
			(at 0 -6.3754 90)
			(unlocked yes)
			(layer "F.Fab")
			(hide yes)
			(effects
				(font
					(size 1.016 1.016)
					(thickness 0.1524)
				)
			)
		)
		(duplicate_pad_numbers_are_jumpers no)
		(fp_line
			(start 1.016 -2.2352)
			(end 1.016 2.2352)
			(stroke
				(width 0.1524)
				(type default)
			)
			(layer "F.SilkS")
		)
		(fp_line
			(start -1.016 -2.2352)
			(end 1.016 -2.2352)
			(stroke
				(width 0.1524)
				(type default)
			)
			(layer "F.SilkS")
		)
		(fp_line
			(start 1.016 2.2352)
			(end -1.016 2.2352)
			(stroke
				(width 0.1524)
				(type default)
			)
			(layer "F.SilkS")
		)
		(fp_line
			(start -1.016 2.2352)
			(end -1.016 -2.2352)
			(stroke
				(width 0.1524)
				(type default)
			)
			(layer "F.SilkS")
		)
		(fp_rect
			(start -1.0922 2.3114)
			(end 1.0922 -2.3114)
			(stroke
				(width 0)
				(type default)
			)
			(fill no)
			(layer "F.CrtYd")
		)
		(fp_poly
			(pts
				(xy -1.0922 -2.3114) (xy 1.0922 -2.3114) (xy 1.0922 2.3114) (xy -1.0922 2.3114)
			)
			(stroke
				(width 0)
				(type default)
			)
			(fill no)
			(layer "F.Fab")
		)
		(pad "1" smd rect
			(at 0 -1.397 90)
			(size 1.651 1.27)
			(layers "F.Cu" "F.Mask" "F.Paste")
			(net "P12V_HDD25")
		)
		(pad "2" smd rect
			(at 0 1.397 90)
			(size 1.651 1.27)
			(layers "F.Cu" "F.Mask" "F.Paste")
			(net "12V_PRE_25")
		)
	)
	(footprint ""
		(layer "F.Cu")
		(at 416.284664 -129.66065 -90)
		(property "Reference" "C302"
			(at 0 0 270)
			(layer "F.SilkS")
			(hide yes)
			(effects
				(font
					(size 1.27 1.27)
				)
			)
		)
		(property "Value" "SCD01U16V1KX-GP"
			(at -2.8321 -1.7399 270)
			(unlocked yes)
			(layer "F.Fab")
			(hide yes)
			(effects
				(font
					(size 1.016 1.016)
					(thickness 0.1524)
				)
			)
		)
		(property "Device Type" "C0201H13"
			(at -2.8321 -3.2639 270)
			(unlocked yes)
			(layer "F.Fab")
			(hide yes)
			(effects
				(font
					(size 1.016 1.016)
					(thickness 0.1524)
				)
			)
		)
		(duplicate_pad_numbers_are_jumpers no)
		(fp_rect
			(start -0.2794 0.6477)
			(end 0.2794 -0.6477)
			(stroke
				(width 0)
				(type default)
			)
			(fill no)
			(layer "F.CrtYd")
		)
		(fp_rect
			(start -0.2794 0.6477)
			(end 0.2794 -0.6477)
			(stroke
				(width 0)
				(type default)
			)
			(fill no)
			(layer "F.Fab")
		)
		(pad "1" smd custom
			(at 0 -0.2794 270)
			(size 0.0762 0.0762)
			(layers "F.Cu" "F.Mask" "F.Paste")
			(net "SAS_HDD_RX_P21")
			(options
				(clearance outline)
				(anchor circle)
			)
			(primitives
				(gr_poly
					(pts
						(arc
							(start 0.1524 -0.127)
							(mid 0.137521 -0.162921)
							(end 0.1016 -0.1778)
						)
						(arc
							(start -0.1016 -0.1778)
							(mid -0.137521 -0.162921)
							(end -0.1524 -0.127)
						)
						(arc
							(start -0.1524 0.127)
							(mid -0.137521 0.162921)
							(end -0.1016 0.1778)
						)
						(arc
							(start 0.1016 0.1778)
							(mid 0.137521 0.162921)
							(end 0.1524 0.127)
						)
					)
					(width 0)
					(fill yes)
				)
			)
		)
		(pad "2" smd custom
			(at 0 0.2794 270)
			(size 0.0762 0.0762)
			(layers "F.Cu" "F.Mask" "F.Paste")
			(net "PHY_SCC_B_TO_DRV_B_21_DP")
			(options
				(clearance outline)
				(anchor circle)
			)
			(primitives
				(gr_poly
					(pts
						(arc
							(start 0.1524 -0.127)
							(mid 0.137521 -0.162921)
							(end 0.1016 -0.1778)
						)
						(arc
							(start -0.1016 -0.1778)
							(mid -0.137521 -0.162921)
							(end -0.1524 -0.127)
						)
						(arc
							(start -0.1524 0.127)
							(mid -0.137521 0.162921)
							(end -0.1016 0.1778)
						)
						(arc
							(start 0.1016 0.1778)
							(mid 0.137521 0.162921)
							(end 0.1524 0.127)
						)
					)
					(width 0)
					(fill yes)
				)
			)
		)
	)
	(footprint ""
		(layer "F.Cu")
		(at 55.753 -45.466 180)
		(property "Reference" "C361"
			(at 0 0 180)
			(layer "F.SilkS")
			(hide yes)
			(effects
				(font
					(size 1.27 1.27)
				)
			)
		)
		(property "Value" "SC1U25V3KX-GP"
			(at 0 -2.8194 180)
			(unlocked yes)
			(layer "F.Fab")
			(hide yes)
			(effects
				(font
					(size 1.016 1.016)
					(thickness 0.1524)
				)
			)
		)
		(property "Device Type" "C603H36"
			(at 0 -4.3434 180)
			(unlocked yes)
			(layer "F.Fab")
			(hide yes)
			(effects
				(font
					(size 1.016 1.016)
					(thickness 0.1524)
				)
			)
		)
		(duplicate_pad_numbers_are_jumpers no)
		(fp_line
			(start 0.508 0)
			(end -0.508 0)
			(stroke
				(width 0.2032)
				(type default)
			)
			(layer "F.SilkS")
		)
		(fp_rect
			(start -0.5842 1.3335)
			(end 0.5842 -1.3335)
			(stroke
				(width 0)
				(type default)
			)
			(fill no)
			(layer "F.CrtYd")
		)
		(fp_rect
			(start -0.5842 1.3335)
			(end 0.5842 -1.3335)
			(stroke
				(width 0)
				(type default)
			)
			(fill no)
			(layer "F.Fab")
		)
		(pad "1" smd custom
			(at 0 -0.762 180)
			(size 0.2159 0.2159)
			(layers "F.Cu" "F.Mask" "F.Paste")
			(net "P12V_HDD25")
			(options
				(clearance outline)
				(anchor circle)
			)
			(primitives
				(gr_poly
					(pts
						(arc
							(start -0.3302 -0.4318)
							(mid -0.402042 -0.402042)
							(end -0.4318 -0.3302)
						)
						(arc
							(start -0.4318 0.3302)
							(mid -0.402042 0.402042)
							(end -0.3302 0.4318)
						)
						(arc
							(start 0.3302 0.4318)
							(mid 0.402042 0.402042)
							(end 0.4318 0.3302)
						)
						(arc
							(start 0.4318 -0.3302)
							(mid 0.402042 -0.402042)
							(end 0.3302 -0.4318)
						)
					)
					(width 0)
					(fill yes)
				)
			)
		)
		(pad "2" smd custom
			(at 0 0.762 180)
			(size 0.2159 0.2159)
			(layers "F.Cu" "F.Mask" "F.Paste")
			(net "GND")
			(options
				(clearance outline)
				(anchor circle)
			)
			(primitives
				(gr_poly
					(pts
						(arc
							(start -0.3302 -0.4318)
							(mid -0.402042 -0.402042)
							(end -0.4318 -0.3302)
						)
						(arc
							(start -0.4318 0.3302)
							(mid -0.402042 0.402042)
							(end -0.3302 0.4318)
						)
						(arc
							(start 0.3302 0.4318)
							(mid 0.402042 0.402042)
							(end 0.4318 0.3302)
						)
						(arc
							(start 0.4318 -0.3302)
							(mid 0.402042 -0.402042)
							(end 0.3302 -0.4318)
						)
					)
					(width 0)
					(fill yes)
				)
			)
		)
	)
	(footprint ""
		(layer "F.Cu")
		(at 14.732 -35.687 -90)
		(property "Reference" "C346"
			(at 0 0 270)
			(layer "F.SilkS")
			(hide yes)
			(effects
				(font
					(size 1.27 1.27)
				)
			)
		)
		(property "Value" "SC4D7U25V5KX-1-GP"
			(at -0.0762 -6.1214 270)
			(unlocked yes)
			(layer "F.Fab")
			(hide yes)
			(effects
				(font
					(size 1.016 1.016)
					(thickness 0.1524)
				)
			)
		)
		(property "Device Type" "C805H58"
			(at -0.0762 -8.1534 270)
			(unlocked yes)
			(layer "F.Fab")
			(hide yes)
			(effects
				(font
					(size 1.016 1.016)
					(thickness 0.1524)
				)
			)
		)
		(duplicate_pad_numbers_are_jumpers no)
		(fp_line
			(start 0.635 0)
			(end -0.635 0)
			(stroke
				(width 0.508)
				(type default)
			)
			(layer "F.SilkS")
		)
		(fp_rect
			(start -0.9652 1.778)
			(end 0.9652 -1.778)
			(stroke
				(width 0)
				(type default)
			)
			(fill no)
			(layer "F.CrtYd")
		)
		(fp_poly
			(pts
				(xy -0.9652 -1.778) (xy 0.9652 -1.778) (xy 0.9652 1.778) (xy -0.9652 1.778)
			)
			(stroke
				(width 0)
				(type default)
			)
			(fill no)
			(layer "F.Fab")
		)
		(pad "1" smd rect
			(at 0 -0.9652 270)
			(size 1.397 1.143)
			(layers "F.Cu" "F.Mask" "F.Paste")
			(net "P12V_HDD24")
		)
		(pad "2" smd rect
			(at 0 0.9652 270)
			(size 1.397 1.143)
			(layers "F.Cu" "F.Mask" "F.Paste")
			(net "GND")
		)
	)
	(footprint ""
		(layer "F.Cu")
		(at 172.593 -131.572 90)
		(property "Reference" "R475"
			(at 0 0 90)
			(layer "F.SilkS")
			(hide yes)
			(effects
				(font
					(size 1.27 1.27)
				)
			)
		)
		(property "Value" "4K7R2J-2-GP"
			(at 0.064008 -3.993896 90)
			(unlocked yes)
			(layer "F.Fab")
			(hide yes)
			(effects
				(font
					(size 1.016 1.016)
					(thickness 0.1524)
				)
			)
		)
		(property "Device Type" "R402H16"
			(at 0.064008 -5.517896 90)
			(unlocked yes)
			(layer "F.Fab")
			(hide yes)
			(effects
				(font
					(size 1.016 1.016)
					(thickness 0.1524)
				)
			)
		)
		(duplicate_pad_numbers_are_jumpers no)
		(fp_line
			(start 0.508 -0.9398)
			(end -0.508 -0.9398)
			(stroke
				(width 0.1524)
				(type default)
			)
			(layer "F.SilkS")
		)
		(fp_line
			(start -0.508 -0.9398)
			(end -0.508 0.9398)
			(stroke
				(width 0.1524)
				(type default)
			)
			(layer "F.SilkS")
		)
		(fp_rect
			(start -0.508 0.9398)
			(end 0.508 -0.9398)
			(stroke
				(width 0)
				(type default)
			)
			(fill no)
			(layer "F.CrtYd")
		)
		(fp_rect
			(start -0.508 0.9398)
			(end 0.508 -0.9398)
			(stroke
				(width 0)
				(type default)
			)
			(fill no)
			(layer "F.Fab")
		)
		(pad "1" smd custom
			(at 0 -0.4445 90)
			(size 0.1397 0.1397)
			(layers "F.Cu" "F.Mask" "F.Paste")
			(net "P12V_B")
			(options
				(clearance outline)
				(anchor circle)
			)
			(primitives
				(gr_poly
					(pts
						(arc
							(start -0.1778 -0.2794)
							(mid -0.249642 -0.249642)
							(end -0.2794 -0.1778)
						)
						(arc
							(start -0.2794 0.1778)
							(mid -0.249642 0.249642)
							(end -0.1778 0.2794)
						)
						(arc
							(start 0.1778 0.2794)
							(mid 0.249642 0.249642)
							(end 0.2794 0.1778)
						)
						(arc
							(start 0.2794 -0.1778)
							(mid 0.249642 -0.249642)
							(end 0.1778 -0.2794)
						)
					)
					(width 0)
					(fill yes)
				)
			)
		)
		(pad "2" smd custom
			(at 0 0.4445 90)
			(size 0.1397 0.1397)
			(layers "F.Cu" "F.Mask" "F.Paste")
			(net "SW_HDD_R17")
			(options
				(clearance outline)
				(anchor circle)
			)
			(primitives
				(gr_poly
					(pts
						(arc
							(start -0.1778 -0.2794)
							(mid -0.249642 -0.249642)
							(end -0.2794 -0.1778)
						)
						(arc
							(start -0.2794 0.1778)
							(mid -0.249642 0.249642)
							(end -0.1778 0.2794)
						)
						(arc
							(start 0.1778 0.2794)
							(mid 0.249642 0.249642)
							(end 0.2794 0.1778)
						)
						(arc
							(start 0.2794 -0.1778)
							(mid 0.249642 -0.249642)
							(end 0.1778 -0.2794)
						)
					)
					(width 0)
					(fill yes)
				)
			)
		)
	)
)
